# SCM (Grand Teton) — schematic netlist excerpt (pin names and nets, part order shuffled) for the footprints in the layout excerpt that follows; sources: Cadence DE-HDL packaged netlist, KiCad conversion of 12092022_DA0F0TMDCD0_F0T_Management_Board_D_brd_V3_OCP.brd

R451  Q_RES  0 5% CHIP  pkg 0402LF  page 22 : A = PWRGD_P1V0_AUX_DELAY ; B = PWRGD_P1V0_AUX_DELAY_R1
R218  Q_RES  0 5% CHIP  pkg 0402LF  page 15 : A = USB_HOST_BMC_A_R_DN ; B = USB_HOST_BMC_A_DN

(kicad_pcb
	(version 20260206)
	(generator "pcbnew")
	(generator_version "10.0")
	(general
		(thickness 1.6)
		(legacy_teardrops no)
	)
	(paper "A4")
	(title_block
		(title "12092022_DA0F0TMDCD0_F0T_Management_Board_D_brd_V3_OCP.brd")
		(comment 1 "Grand Teton / footprints 529-530 of 1440")
	)
	(layers
		(0 "F.Cu" signal "TOP")
		(4 "In1.Cu" signal "GND")
		(6 "In2.Cu" signal "IN1")
		(8 "In3.Cu" signal "GND1")
		(10 "In4.Cu" signal "IN2")
		(12 "In5.Cu" signal "VCC")
		(14 "In6.Cu" signal "VCC1")
		(16 "In7.Cu" signal "IN3")
		(18 "In8.Cu" signal "GND2")
		(20 "In9.Cu" signal "IN4")
		(22 "In10.Cu" signal "GND3")
		(2 "B.Cu" signal "BOTTOM")
		(9 "F.Adhes" user "F.Adhesive")
		(11 "B.Adhes" user "B.Adhesive")
		(13 "F.Paste" user "Package Geometry/Pastemask Top")
		(15 "B.Paste" user "Package Geometry/Pastemask Bottom")
		(5 "F.SilkS" user "Ref Des/Silkscreen Top")
		(7 "B.SilkS" user "Ref Des/Silkscreen Bottom")
		(1 "F.Mask" user "Board Geometry/Soldermask Top")
		(3 "B.Mask" user "Board Geometry/Soldermask Bottom")
		(17 "Dwgs.User" user "User.Drawings")
		(19 "Cmts.User" user "User.Comments")
		(21 "Eco1.User" user "User.Eco1")
		(23 "Eco2.User" user "User.Eco2")
		(25 "Edge.Cuts" user "Board Geometry/Outline")
		(27 "Margin" user)
		(31 "F.CrtYd" user "Package Geometry/Place Bound Top")
		(29 "B.CrtYd" user "Package Geometry/Place Bound Bottom")
		(35 "F.Fab" user "Ref Des/Assembly Top")
		(33 "B.Fab" user "Ref Des/Assembly Bottom")
	)
	(footprint ""
		(layer "F.Cu")
		(at 65.618106 -29.377132 -90)
		(property "Reference" "R218"
			(at 0 0 270)
			(layer "F.SilkS")
			(hide yes)
			(effects
				(font
					(size 1.27 1.27)
				)
			)
		)
		(property "Value" ""
			(at 0 0 270)
			(layer "F.Fab")
			(effects
				(font
					(size 1.27 1.27)
				)
			)
		)
		(duplicate_pad_numbers_are_jumpers no)
		(fp_line
			(start 0.458978 0.4064)
			(end -0.397002 0.4064)
			(stroke
				(width 0.1524)
				(type default)
			)
			(layer "F.SilkS")
		)
		(fp_line
			(start -0.7874 0.060706)
			(end -0.7874 -0.4064)
			(stroke
				(width 0.1524)
				(type default)
			)
			(layer "F.SilkS")
		)
		(fp_line
			(start -0.7874 -0.4064)
			(end 0.7874 -0.4064)
			(stroke
				(width 0.1524)
				(type default)
			)
			(layer "F.SilkS")
		)
		(fp_line
			(start 0.7874 -0.4064)
			(end 0.7874 -0.010414)
			(stroke
				(width 0.1524)
				(type default)
			)
			(layer "F.SilkS")
		)
		(fp_line
			(start -0.67945 0.3048)
			(end -0.67945 -0.305054)
			(stroke
				(width 0.1)
				(type default)
			)
			(layer "F.Fab")
		)
		(fp_line
			(start -0.12065 0.3048)
			(end -0.67945 0.3048)
			(stroke
				(width 0.1)
				(type default)
			)
			(layer "F.Fab")
		)
		(fp_line
			(start 0.120396 0.3048)
			(end 0.120396 0.2794)
			(stroke
				(width 0.1)
				(type default)
			)
			(layer "F.Fab")
		)
		(fp_line
			(start 0.67945 0.3048)
			(end 0.120396 0.3048)
			(stroke
				(width 0.1)
				(type default)
			)
			(layer "F.Fab")
		)
		(fp_line
			(start -0.12065 0.2794)
			(end -0.12065 0.3048)
			(stroke
				(width 0.1)
				(type default)
			)
			(layer "F.Fab")
		)
		(fp_line
			(start 0.120396 0.2794)
			(end -0.12065 0.2794)
			(stroke
				(width 0.1)
				(type default)
			)
			(layer "F.Fab")
		)
		(fp_line
			(start -0.12065 -0.2794)
			(end 0.12065 -0.2794)
			(stroke
				(width 0.1)
				(type default)
			)
			(layer "F.Fab")
		)
		(fp_line
			(start 0.12065 -0.2794)
			(end 0.12065 -0.3048)
			(stroke
				(width 0.1)
				(type default)
			)
			(layer "F.Fab")
		)
		(fp_line
			(start 0.12065 -0.3048)
			(end 0.67945 -0.3048)
			(stroke
				(width 0.1)
				(type default)
			)
			(layer "F.Fab")
		)
		(fp_line
			(start 0.67945 -0.3048)
			(end 0.67945 0.3048)
			(stroke
				(width 0.1)
				(type default)
			)
			(layer "F.Fab")
		)
		(fp_line
			(start -0.67945 -0.305054)
			(end -0.12065 -0.305054)
			(stroke
				(width 0.1)
				(type default)
			)
			(layer "F.Fab")
		)
		(fp_line
			(start -0.12065 -0.305054)
			(end -0.12065 -0.2794)
			(stroke
				(width 0.1)
				(type default)
			)
			(layer "F.Fab")
		)
		(pad "1" smd circle
			(at -0.40005 0 270)
			(size 0 0)
			(layers "F.Cu" "F.Mask" "F.Paste")
			(net "USB_HOST_BMC_A_R_DN")
		)
		(pad "2" smd circle
			(at 0.40005 0 270)
			(size 0 0)
			(layers "F.Cu" "F.Mask" "F.Paste")
			(net "USB_HOST_BMC_A_DN")
		)
	)
	(footprint ""
		(layer "F.Cu")
		(at 32.893 -36.195 90)
		(property "Reference" "R451"
			(at 0 0 90)
			(layer "F.SilkS")
			(hide yes)
			(effects
				(font
					(size 1.27 1.27)
				)
			)
		)
		(property "Value" ""
			(at 0 0 90)
			(layer "F.Fab")
			(effects
				(font
					(size 1.27 1.27)
				)
			)
		)
		(duplicate_pad_numbers_are_jumpers no)
		(fp_line
			(start 0.7874 -0.4064)
			(end 0.7874 0.4064)
			(stroke
				(width 0.1524)
				(type default)
			)
			(layer "F.SilkS")
		)
		(fp_line
			(start -0.7874 -0.4064)
			(end 0.7874 -0.4064)
			(stroke
				(width 0.1524)
				(type default)
			)
			(layer "F.SilkS")
		)
		(fp_line
			(start 0.7874 0.4064)
			(end -0.7874 0.4064)
			(stroke
				(width 0.1524)
				(type default)
			)
			(layer "F.SilkS")
		)
		(fp_line
			(start -0.7874 0.4064)
			(end -0.7874 -0.4064)
			(stroke
				(width 0.1524)
				(type default)
			)
			(layer "F.SilkS")
		)
		(fp_line
			(start -0.12065 -0.305054)
			(end -0.12065 -0.2794)
			(stroke
				(width 0.1)
				(type default)
			)
			(layer "F.Fab")
		)
		(fp_line
			(start -0.67945 -0.305054)
			(end -0.12065 -0.305054)
			(stroke
				(width 0.1)
				(type default)
			)
			(layer "F.Fab")
		)
		(fp_line
			(start 0.67945 -0.3048)
			(end 0.67945 0.3048)
			(stroke
				(width 0.1)
				(type default)
			)
			(layer "F.Fab")
		)
		(fp_line
			(start 0.12065 -0.3048)
			(end 0.67945 -0.3048)
			(stroke
				(width 0.1)
				(type default)
			)
			(layer "F.Fab")
		)
		(fp_line
			(start 0.12065 -0.2794)
			(end 0.12065 -0.3048)
			(stroke
				(width 0.1)
				(type default)
			)
			(layer "F.Fab")
		)
		(fp_line
			(start -0.12065 -0.2794)
			(end 0.12065 -0.2794)
			(stroke
				(width 0.1)
				(type default)
			)
			(layer "F.Fab")
		)
		(fp_line
			(start 0.120396 0.2794)
			(end -0.12065 0.2794)
			(stroke
				(width 0.1)
				(type default)
			)
			(layer "F.Fab")
		)
		(fp_line
			(start -0.12065 0.2794)
			(end -0.12065 0.3048)
			(stroke
				(width 0.1)
				(type default)
			)
			(layer "F.Fab")
		)
		(fp_line
			(start 0.67945 0.3048)
			(end 0.120396 0.3048)
			(stroke
				(width 0.1)
				(type default)
			)
			(layer "F.Fab")
		)
		(fp_line
			(start 0.120396 0.3048)
			(end 0.120396 0.2794)
			(stroke
				(width 0.1)
				(type default)
			)
			(layer "F.Fab")
		)
		(fp_line
			(start -0.12065 0.3048)
			(end -0.67945 0.3048)
			(stroke
				(width 0.1)
				(type default)
			)
			(layer "F.Fab")
		)
		(fp_line
			(start -0.67945 0.3048)
			(end -0.67945 -0.305054)
			(stroke
				(width 0.1)
				(type default)
			)
			(layer "F.Fab")
		)
		(pad "1" smd circle
			(at -0.40005 0 90)
			(size 0 0)
			(layers "F.Cu" "F.Mask" "F.Paste")
			(net "PWRGD_P1V0_AUX_DELAY")
		)
		(pad "2" smd circle
			(at 0.40005 0 90)
			(size 0 0)
			(layers "F.Cu" "F.Mask" "F.Paste")
			(net "PWRGD_P1V0_AUX_DELAY_R1")
		)
	)
)
